(kicad_pcb
	(version 20211014)
	(generator pcbnew)
	(general
    (thickness 1.6)
  )
	(paper "A4")
	(title_block
    (title "SA800U (Snapdragon 845) Baseboard")
    (date "2023-10-19")
    (rev "1.0.3")
    (company "Antmicro Ltd.")
    (comment 1 "www.antmicro.com")
		(comment 9 "footprints 150-156 of 589")
	)
	(layers
    (0 "F.Cu" signal)
    (1 "In1.Cu" power)
    (2 "In2.Cu" signal)
    (3 "In3.Cu" signal)
    (4 "In4.Cu" power)
    (31 "B.Cu" signal)
    (32 "B.Adhes" user "B.Adhesive")
    (33 "F.Adhes" user "F.Adhesive")
    (34 "B.Paste" user)
    (35 "F.Paste" user)
    (36 "B.SilkS" user "B.Silkscreen")
    (37 "F.SilkS" user "F.Silkscreen")
    (38 "B.Mask" user)
    (39 "F.Mask" user)
    (40 "Dwgs.User" user "User.Drawings")
    (41 "Cmts.User" user "User.Comments")
    (42 "Eco1.User" user "User.Eco1")
    (43 "Eco2.User" user "User.Eco2")
    (44 "Edge.Cuts" user)
    (45 "Margin" user)
    (46 "B.CrtYd" user "B.Courtyard")
    (47 "F.CrtYd" user "F.Courtyard")
    (48 "B.Fab" user)
    (49 "F.Fab" user)
  )
	(footprint "sa800u-baseboard-hw-footprints:R_0402_1005Metric" (layer "F.Cu")
    (tedit 5FD9C158)
    (at 79.9 125.9)
    (descr "Resistor SMD 0402")
    (tags "resistor SMD 0402")
    (property "Author" "Antmicro")
    (property "License" "Apache-2.0")
    (property "MPN" "CR0402-FX-1372GLF")
    (property "Manufacturer" "Bourns")
    (property "Sheetfile" "psu.kicad_sch")
    (property "Sheetname" "PSU")
    (property "Tolerance" "1%")
    (property "Val" "13k7")
    (attr smd)
    (fp_text reference "R114" (at -1.22 6.2) (layer "F.SilkS")
      (effects (font (size 0.7 0.7) (thickness 0.15)) (justify left bottom))
    )
    (fp_text value "R_13k7_0402" (at 0 1.4) (layer "F.Fab")
      (effects (font (size 0.7 0.7) (thickness 0.15)) (justify left bottom))
    )
    (fp_text user "${REFERENCE}" (at -0.95 3.168) (layer "F.Fab") hide
      (effects (font (size 0.7 0.7) (thickness 0.15)) (justify left bottom))
    )
    (fp_text user "Author: Antmicro" (at -0.95 4.169) (layer "F.Fab") hide
      (effects (font (size 0.7 0.7) (thickness 0.15)) (justify left bottom))
    )
    (fp_text user "License: Apache-2.0" (at -0.95 5.169) (layer "F.Fab") hide
      (effects (font (size 0.7 0.7) (thickness 0.15)) (justify left bottom))
    )
    (fp_rect (start -0.93 -0.47) (end 0.93 0.47) (layer "F.CrtYd") (width 0.05) (fill none))
    (fp_rect (start -0.5 -0.25) (end 0.5 0.25) (layer "F.Fab") (width 0.15) (fill none))
    (pad "1" smd roundrect (at -0.485 0) (size 0.59 0.64) (layers "F.Cu" "F.Paste" "F.Mask") (roundrect_rratio 0.25)
      (net 403 "Net-(R113-Pad2)") (pintype "passive"))
    (pad "2" smd roundrect (at 0.485 0) (size 0.59 0.64) (layers "F.Cu" "F.Paste" "F.Mask") (roundrect_rratio 0.25)
      (net 1 "GND") (pintype "passive"))
  )
	(footprint "sa800u-baseboard-hw-footprints:CONV_PDQE30-Q48-S5-D" locked (layer "F.Cu")
    (tedit 608ACD31)
    (at 57.842 84.841)
    (property "Author" "Antmicro")
    (property "License" "Apache-2.0")
    (property "MPN" "PDQE30-Q48-S5-D")
    (property "Manufacturer" "CUI Inc")
    (property "STANDARD" "Manufacturer Recommendations")
    (property "Sheetfile" "poe.kicad_sch")
    (property "Sheetname" "PoE")
    (attr through_hole)
    (fp_text reference "PS1" (at 23.558 -1.391 270) (layer "F.SilkS")
      (effects (font (size 0.65 0.65) (thickness 0.15)))
    )
    (fp_text value "PDQE30-Q48-S5-D" (at 0.16 14.155) (layer "F.Fab") hide
      (effects (font (size 1 1) (thickness 0.15)))
    )
    (fp_text user "${REFERENCE}" (at -3.912 28.711) (layer "F.Fab") hide
      (effects (font (size 0.7 0.7) (thickness 0.15)) (justify left bottom))
    )
    (fp_text user "Author: Antmicro" (at -3.912 26.312) (layer "F.Fab") hide
      (effects (font (size 0.7 0.7) (thickness 0.15)) (justify left bottom))
    )
    (fp_text user "License: Apache-2.0" (at -3.912 27.51) (layer "F.Fab") hide
      (effects (font (size 0.7 0.7) (thickness 0.15)) (justify left bottom))
    )
    (fp_line (start 22.859 22.859) (end -2.54 22.859) (layer "F.SilkS") (width 0.15))
    (fp_line (start 22.859 -2.54) (end 22.859 22.859) (layer "F.SilkS") (width 0.15))
    (fp_line (start -2.54 22.859) (end -2.54 -2.54) (layer "F.SilkS") (width 0.15))
    (fp_line (start -2.54 -2.54) (end 22.859 -2.54) (layer "F.SilkS") (width 0.15))
    (fp_circle (center -2.4 -2.9) (end -2.35 -2.9) (layer "F.SilkS") (width 0.15) (fill solid))
    (fp_rect (start -2.667 -2.667) (end 22.987 22.987) (layer "F.CrtYd") (width 0.05) (fill none))
    (fp_line (start 22.859 22.859) (end -2.54 22.859) (layer "F.Fab") (width 0.15))
    (fp_line (start 22.859 -2.54) (end 22.859 22.859) (layer "F.Fab") (width 0.15))
    (fp_line (start -2.54 -2.54) (end 22.859 -2.54) (layer "F.Fab") (width 0.15))
    (fp_line (start -2.54 22.859) (end -2.54 -2.54) (layer "F.Fab") (width 0.15))
    (pad "1" thru_hole rect locked (at 0 0) (size 2.25 2.25) (drill 1.5) (layers *.Cu *.Mask)
      (net 76 "/PoE/SMPS_CTRL") (pinfunction "CTRL") (pintype "input"))
    (pad "2" thru_hole circle locked (at 0 7.618) (size 2.25 2.25) (drill 1.5) (layers *.Cu *.Mask)
      (net 7 "GNDD") (pinfunction "GND") (pintype "power_in"))
    (pad "3" thru_hole circle locked (at 0 12.698) (size 2.25 2.25) (drill 1.5) (layers *.Cu *.Mask)
      (net 73 "/PoE/VDD_POE") (pinfunction "V_{IN}") (pintype "power_in"))
    (pad "4" thru_hole circle locked (at 20.318 20.318) (size 2.25 2.25) (drill 1.5) (layers *.Cu *.Mask)
      (net 136 "5V_POE") (pinfunction "V_{O}") (pintype "power_out"))
    (pad "5" thru_hole circle locked (at 20.318 10.159) (size 2.25 2.25) (drill 1.5) (layers *.Cu *.Mask)
      (net 153 "/PoE/TRIM") (pinfunction "TRIM") (pintype "passive"))
    (pad "6" thru_hole circle locked (at 20.318 0) (size 2.25 2.25) (drill 1.5) (layers *.Cu *.Mask)
      (net 1 "GND") (pinfunction "0V") (pintype "power_out"))
  )
	(footprint "sa800u-baseboard-hw-footprints:LED_0603_1608Metric_G" (layer "F.Cu")
    (tedit 60C2DD7B)
    (at 82.6 107.3)
    (descr "LED SMD 0603 Green")
    (tags "LED SMD 0603 Green")
    (property "Author" "Antmicro")
    (property "License" "Apache-2.0")
    (property "MPN" "KP-1608ZGC")
    (property "Manufacturer" "Kingbright")
    (property "Sheetfile" "psu.kicad_sch")
    (property "Sheetname" "PSU")
    (attr smd)
    (fp_text reference "D26" (at -1.04 -0.74) (layer "F.SilkS")
      (effects (font (size 0.7 0.7) (thickness 0.15)) (justify left bottom))
    )
    (fp_text value "KP-1608EC" (at 0 1.6) (layer "F.Fab")
      (effects (font (size 0.7 0.7) (thickness 0.15)) (justify left bottom))
    )
    (fp_text user "License: Apache-2.0" (at -1.31 5.769) (layer "F.Fab") hide
      (effects (font (size 0.7 0.7) (thickness 0.15)) (justify left bottom))
    )
    (fp_text user "${REFERENCE}" (at -1.31 3.769) (layer "F.Fab") hide
      (effects (font (size 0.7 0.7) (thickness 0.15)) (justify left bottom))
    )
    (fp_text user "Author: Antmicro" (at -1.31 4.769) (layer "F.Fab") hide
      (effects (font (size 0.7 0.7) (thickness 0.15)) (justify left bottom))
    )
    (fp_line (start -0.27 0.351) (end 0.27 0.351) (layer "F.SilkS") (width 0.15))
    (fp_line (start -0.27 -0.35) (end 0.27 -0.35) (layer "F.SilkS") (width 0.15))
    (fp_line (start 0.093672 -0.000008) (end 0.293672 -0.000008) (layer "F.SilkS") (width 0.1))
    (fp_line (start -0.106328 -0.200008) (end -0.106328 0.199992) (layer "F.SilkS") (width 0.1))
    (fp_line (start -0.106328 -0.200008) (end 0.093672 -0.000008) (layer "F.SilkS") (width 0.1))
    (fp_line (start -0.106328 -0.000008) (end -0.29 0) (layer "F.SilkS") (width 0.1))
    (fp_line (start 1.25 0.32) (end 1.25 -0.32) (layer "F.SilkS") (width 0.15))
    (fp_line (start 0.093672 -0.200008) (end 0.093672 0.199992) (layer "F.SilkS") (width 0.1))
    (fp_line (start 0.093672 -0.000008) (end -0.106328 0.199992) (layer "F.SilkS") (width 0.1))
    (fp_rect (start 1.26 0.65) (end -1.26 -0.65) (layer "F.CrtYd") (width 0.05) (fill none))
    (fp_line (start 0.199 0) (end 0.597 0) (layer "F.Fab") (width 0.15))
    (fp_line (start -0.599 0) (end -0.201 0) (layer "F.Fab") (width 0.15))
    (fp_line (start 0.101 0) (end -0.201 -0.2) (layer "F.Fab") (width 0.15))
    (fp_line (start 0.199 0.202) (end 0.199 -0.1) (layer "F.Fab") (width 0.15))
    (fp_line (start 0.199 -0.2) (end 0.199 -0.1) (layer "F.Fab") (width 0.15))
    (fp_line (start -0.201 0) (end -0.201 0.202) (layer "F.Fab") (width 0.15))
    (fp_line (start -0.201 -0.2) (end -0.201 0) (layer "F.Fab") (width 0.15))
    (fp_line (start -0.201 0.202) (end 0.101 0) (layer "F.Fab") (width 0.15))
    (fp_rect (start -0.848 -0.4) (end 0.85 0.402) (layer "F.Fab") (width 0.15) (fill none))
    (pad "1" smd rect (at -0.75 0 180) (size 0.8 0.8) (layers "F.Cu" "F.Paste" "F.Mask")
      (net 136 "5V_POE") (pinfunction "1") (pintype "passive"))
    (pad "2" smd rect (at 0.75 0 180) (size 0.8 0.8) (layers "F.Cu" "F.Paste" "F.Mask")
      (net 377 "Net-(D26-Pad2)") (pinfunction "2") (pintype "passive"))
  )
	(footprint "sa800u-baseboard-hw-footprints:Nexperia_DFN-10_2.5x1mm_P0.5mm" (layer "F.Cu")
    (tedit 6215DC23)
    (at 145.25 139.55 180)
    (property "Author" "Antmicro")
    (property "License" "Apache-2.0")
    (property "MPN" "PUSB3F96X")
    (property "Manufacturer" "Nexperia")
    (property "Sheetfile" "hdmi-converter.kicad_sch")
    (property "Sheetname" "HDMI converter")
    (attr smd)
    (fp_text reference "D5" (at 1.52 0.8 180) (layer "F.SilkS")
      (effects (font (size 0.7 0.7) (thickness 0.15)) (justify left bottom))
    )
    (fp_text value "PUSB3F96X_PASS" (at -0.016 1.705 180) (layer "F.Fab")
      (effects (font (size 0.7 0.7) (thickness 0.15)) (justify left bottom))
    )
    (fp_text user "Author: Antmicro" (at -1.367 4.905 180) (layer "F.Fab") hide
      (effects (font (size 0.7 0.7) (thickness 0.15)) (justify left bottom))
    )
    (fp_text user "${REFERENCE}" (at -1.367 3.704 180) (layer "F.Fab") hide
      (effects (font (size 0.7 0.7) (thickness 0.15)) (justify left bottom))
    )
    (fp_text user "License: Apache-2.0" (at -1.367 6.105 180) (layer "F.Fab") hide
      (effects (font (size 0.7 0.7) (thickness 0.15)) (justify left bottom))
    )
    (fp_line (start -1.266 -0.396) (end -1.266 0.405) (layer "F.SilkS") (width 0.15))
    (fp_line (start 1.233 0.405) (end 1.233 -0.396) (layer "F.SilkS") (width 0.15))
    (fp_circle (center -1.317 0.704) (end -1.266 0.704) (layer "F.SilkS") (width 0.15) (fill solid))
    (fp_rect (start -1.4 -0.7) (end 1.4 0.7) (layer "F.CrtYd") (width 0.05) (fill none))
    (pad "1" smd rect (at -1.016 0.392 180) (size 0.2 0.475) (layers "F.Cu" "F.Paste" "F.Mask")
      (net 243 "/HDMI converter/HDMI_TX2_CONN_P") (pinfunction "CH1") (pintype "passive"))
    (pad "2" smd rect (at -0.517 0.392 180) (size 0.2 0.475) (layers "F.Cu" "F.Paste" "F.Mask")
      (net 240 "/HDMI converter/HDMI_TX2_CONN_N") (pinfunction "CH2") (pintype "passive"))
    (pad "3" smd rect (at -0.016 0.392 180) (size 0.2 0.475) (layers "F.Cu" "F.Paste" "F.Mask")
      (net 1 "GND") (pinfunction "GND") (pintype "passive"))
    (pad "4" smd rect (at 0.482 0.392 180) (size 0.2 0.475) (layers "F.Cu" "F.Paste" "F.Mask")
      (net 241 "/HDMI converter/HDMI_TX1_CONN_P") (pinfunction "CH3") (pintype "passive"))
    (pad "5" smd rect (at 0.982 0.392 180) (size 0.2 0.475) (layers "F.Cu" "F.Paste" "F.Mask")
      (net 242 "/HDMI converter/HDMI_TX1_CONN_N") (pinfunction "CH4") (pintype "passive"))
    (pad "6" smd rect (at 0.982 -0.383) (size 0.2 0.475) (layers "F.Cu" "F.Paste" "F.Mask")
      (net 242 "/HDMI converter/HDMI_TX1_CONN_N") (pinfunction "CH4") (pintype "passive"))
    (pad "7" smd rect (at 0.482 -0.383) (size 0.2 0.475) (layers "F.Cu" "F.Paste" "F.Mask")
      (net 241 "/HDMI converter/HDMI_TX1_CONN_P") (pinfunction "CH3") (pintype "passive"))
    (pad "8" smd rect (at -0.016 -0.383) (size 0.2 0.475) (layers "F.Cu" "F.Paste" "F.Mask")
      (net 1 "GND") (pinfunction "GND") (pintype "passive"))
    (pad "9" smd rect (at -0.517 -0.383) (size 0.2 0.475) (layers "F.Cu" "F.Paste" "F.Mask")
      (net 240 "/HDMI converter/HDMI_TX2_CONN_N") (pinfunction "CH2") (pintype "passive"))
    (pad "10" smd rect (at -1.016 -0.383) (size 0.2 0.475) (layers "F.Cu" "F.Paste" "F.Mask")
      (net 243 "/HDMI converter/HDMI_TX2_CONN_P") (pinfunction "CH1") (pintype "passive"))
  )
	(footprint "sa800u-baseboard-hw-footprints:R_0402_1005Metric" (layer "F.Cu")
    (tedit 5FD9C158)
    (at 81.5 104.15 -90)
    (descr "Resistor SMD 0402")
    (tags "resistor SMD 0402")
    (property "Author" "Antmicro")
    (property "License" "Apache-2.0")
    (property "MPN" "CR0402-FX-1002GLF")
    (property "Manufacturer" "Bourns")
    (property "Sheetfile" "psu.kicad_sch")
    (property "Sheetname" "PSU")
    (property "Tolerance" "1%")
    (property "Val" "10k")
    (attr smd)
    (fp_text reference "R116" (at 1.47 -1.22 -90) (layer "F.SilkS")
      (effects (font (size 0.7 0.7) (thickness 0.15)) (justify left bottom))
    )
    (fp_text value "R_10k_0402" (at 0 1.4 -90) (layer "F.Fab")
      (effects (font (size 0.7 0.7) (thickness 0.15)) (justify left bottom))
    )
    (fp_text user "Author: Antmicro" (at -0.95 4.169 -90) (layer "F.Fab") hide
      (effects (font (size 0.7 0.7) (thickness 0.15)) (justify left bottom))
    )
    (fp_text user "License: Apache-2.0" (at -0.95 5.169 -90) (layer "F.Fab") hide
      (effects (font (size 0.7 0.7) (thickness 0.15)) (justify left bottom))
    )
    (fp_text user "${REFERENCE}" (at -0.95 3.168 -90) (layer "F.Fab") hide
      (effects (font (size 0.7 0.7) (thickness 0.15)) (justify left bottom))
    )
    (fp_rect (start -0.93 -0.47) (end 0.93 0.47) (layer "F.CrtYd") (width 0.05) (fill none))
    (fp_rect (start -0.5 -0.25) (end 0.5 0.25) (layer "F.Fab") (width 0.15) (fill none))
    (pad "1" smd roundrect (at -0.485 0 270) (size 0.59 0.64) (layers "F.Cu" "F.Paste" "F.Mask") (roundrect_rratio 0.25)
      (net 347 "Net-(Q13-Pad3)") (pintype "passive"))
    (pad "2" smd roundrect (at 0.485 0 270) (size 0.59 0.64) (layers "F.Cu" "F.Paste" "F.Mask") (roundrect_rratio 0.25)
      (net 377 "Net-(D26-Pad2)") (pintype "passive"))
  )
	(footprint "sa800u-baseboard-hw-footprints:R_0402_1005Metric" (layer "F.Cu")
    (tedit 5FD9C158)
    (at 90.75 132.65 180)
    (descr "Resistor SMD 0402")
    (tags "resistor SMD 0402")
    (property "Author" "Antmicro")
    (property "License" "Apache-2.0")
    (property "MPN" "CR0402-FX-5100GLF")
    (property "Manufacturer" "Bourns")
    (property "Sheetfile" "usb-pd.kicad_sch")
    (property "Sheetname" "USB-PD")
    (property "Tolerance" "1%")
    (property "Val" "510R")
    (attr smd)
    (fp_text reference "R171" (at 3.52 -0.33 180) (layer "F.SilkS")
      (effects (font (size 0.7 0.7) (thickness 0.15)) (justify left bottom))
    )
    (fp_text value "R_510R_0402" (at 0 1.4 180) (layer "F.Fab")
      (effects (font (size 0.7 0.7) (thickness 0.15)) (justify left bottom))
    )
    (fp_text user "License: Apache-2.0" (at -0.95 5.169 180) (layer "F.Fab") hide
      (effects (font (size 0.7 0.7) (thickness 0.15)) (justify left bottom))
    )
    (fp_text user "${REFERENCE}" (at -0.95 3.168 180) (layer "F.Fab") hide
      (effects (font (size 0.7 0.7) (thickness 0.15)) (justify left bottom))
    )
    (fp_text user "Author: Antmicro" (at -0.95 4.169 180) (layer "F.Fab") hide
      (effects (font (size 0.7 0.7) (thickness 0.15)) (justify left bottom))
    )
    (fp_rect (start -0.93 -0.47) (end 0.93 0.47) (layer "F.CrtYd") (width 0.05) (fill none))
    (fp_rect (start -0.5 -0.25) (end 0.5 0.25) (layer "F.Fab") (width 0.15) (fill none))
    (pad "1" smd roundrect (at -0.485 0 180) (size 0.59 0.64) (layers "F.Cu" "F.Paste" "F.Mask") (roundrect_rratio 0.25)
      (net 381 "Net-(D36-Pad6)") (pintype "passive"))
    (pad "2" smd roundrect (at 0.485 0 180) (size 0.59 0.64) (layers "F.Cu" "F.Paste" "F.Mask") (roundrect_rratio 0.25)
      (net 133 "5V_SYS") (pintype "passive"))
  )
	(footprint "sa800u-baseboard-hw-footprints:C_Elec_10x10.5mm" (layer "F.Cu")
    (tedit 5ED8C968)
    (at 62 113.6 180)
    (descr "SMD capacitor, aluminum electrolytic, 10x10.5mm")
    (tags "capacitor electrolytic")
    (property "Author" "Antmicro")
    (property "Dielectric" "")
    (property "License" "Apache-2.0")
    (property "MPN" "EEEHA2A470UP")
    (property "Manufacturer" "Panasonic")
    (property "Sheetfile" "poe.kicad_sch")
    (property "Sheetname" "PoE")
    (property "Val" "47u/100V")
    (property "Voltage" "")
    (attr smd)
    (fp_text reference "C145" (at 5.71 1.76 270) (layer "F.SilkS")
      (effects (font (size 0.7 0.7) (thickness 0.15)) (justify left bottom))
    )
    (fp_text value "C_47u_ELEC_100V" (at 0 6.299 180) (layer "F.Fab")
      (effects (font (size 0.7 0.7) (thickness 0.15)) (justify left bottom))
    )
    (fp_text user "${REFERENCE}" (at -6.85 8.3 180) (layer "F.Fab") hide
      (effects (font (size 0.7 0.7) (thickness 0.15)) (justify left bottom))
    )
    (fp_text user "Author: Antmicro" (at -6.85 9.499 180) (layer "F.Fab") hide
      (effects (font (size 0.7 0.7) (thickness 0.15)) (justify left bottom))
    )
    (fp_text user "License: Apache-2.0" (at -6.85 10.699 180) (layer "F.Fab") hide
      (effects (font (size 0.7 0.7) (thickness 0.15)) (justify left bottom))
    )
    (fp_line (start 5.36 -5.361) (end 5.36 -1.51) (layer "F.SilkS") (width 0.15))
    (fp_line (start -5.361 4.295) (end -5.361 1.509) (layer "F.SilkS") (width 0.15))
    (fp_line (start -5.361 4.295) (end -4.296 5.36) (layer "F.SilkS") (width 0.15))
    (fp_line (start -4.296 -5.361) (end 5.36 -5.361) (layer "F.SilkS") (width 0.15))
    (fp_line (start -6.85 -2.76) (end -5.6 -2.76) (layer "F.SilkS") (width 0.15))
    (fp_line (start -6.225 -3.385) (end -6.225 -2.135) (layer "F.SilkS") (width 0.15))
    (fp_line (start -4.296 5.36) (end 5.36 5.36) (layer "F.SilkS") (width 0.15))
    (fp_line (start 5.36 5.36) (end 5.36 1.509) (layer "F.SilkS") (width 0.15))
    (fp_line (start -5.361 -4.296) (end -4.296 -5.361) (layer "F.SilkS") (width 0.15))
    (fp_line (start -5.361 -4.296) (end -5.361 -1.51) (layer "F.SilkS") (width 0.15))
    (fp_line (start -5.5 1.49) (end -5.5 4.34) (layer "F.CrtYd") (width 0.05))
    (fp_line (start -6.66 -1.5) (end -6.66 1.49) (layer "F.CrtYd") (width 0.05))
    (fp_line (start -5.5 4.34) (end -4.35 5.49) (layer "F.CrtYd") (width 0.05))
    (fp_line (start -4.35 5.49) (end 5.49 5.49) (layer "F.CrtYd") (width 0.05))
    (fp_line (start 6.65 1.49) (end 5.49 1.49) (layer "F.CrtYd") (width 0.05))
    (fp_line (start -4.35 -5.5) (end 5.49 -5.5) (layer "F.CrtYd") (width 0.05))
    (fp_line (start 6.65 -1.5) (end 6.65 1.49) (layer "F.CrtYd") (width 0.05))
    (fp_line (start -5.5 -4.35) (end -4.35 -5.5) (layer "F.CrtYd") (width 0.05))
    (fp_line (start 5.49 -5.5) (end 5.49 -1.5) (layer "F.CrtYd") (width 0.05))
    (fp_line (start -5.5 -1.5) (end -6.66 -1.5) (layer "F.CrtYd") (width 0.05))
    (fp_line (start -6.66 1.49) (end -5.5 1.49) (layer "F.CrtYd") (width 0.05))
    (fp_line (start -5.5 -4.35) (end -5.5 -1.5) (layer "F.CrtYd") (width 0.05))
    (fp_line (start 5.49 -1.5) (end 6.65 -1.5) (layer "F.CrtYd") (width 0.05))
    (fp_line (start 5.49 1.49) (end 5.49 5.49) (layer "F.CrtYd") (width 0.05))
    (fp_line (start -4.25 -5.25) (end 5.249 -5.25) (layer "F.Fab") (width 0.15))
    (fp_line (start -4.25 5.249) (end 5.249 5.249) (layer "F.Fab") (width 0.15))
    (fp_line (start 5.249 -5.25) (end 5.249 5.249) (layer "F.Fab") (width 0.15))
    (fp_line (start -5.25 -4.25) (end -4.25 -5.25) (layer "F.Fab") (width 0.15))
    (fp_line (start -5.25 4.249) (end -4.25 5.249) (layer "F.Fab") (width 0.15))
    (fp_line (start -4.059 -2.201) (end -4.059 -1.2) (layer "F.Fab") (width 0.15))
    (fp_line (start -4.559 -1.7) (end -3.559 -1.7) (layer "F.Fab") (width 0.15))
    (fp_line (start -5.25 -4.25) (end -5.25 4.249) (layer "F.Fab") (width 0.15))
    (fp_circle (center 0 0) (end 4.999 0) (layer "F.Fab") (width 0.15) (fill none))
    (pad "1" smd roundrect (at -4.201 0 180) (size 4.4 2.5) (layers "F.Cu" "F.Paste" "F.Mask") (roundrect_rratio 0.1)
      (net 73 "/PoE/VDD_POE") (pintype "passive"))
    (pad "2" smd roundrect (at 4.2 0 180) (size 4.4 2.5) (layers "F.Cu" "F.Paste" "F.Mask") (roundrect_rratio 0.1)
      (net 7 "GNDD") (pintype "passive"))
  )
)
